# BASEBOARD_FAB2 (Tioga Pass) — schematic netlist excerpt (pin names and nets, part order shuffled) for the footprints in the layout excerpt that follows; sources: Cadence DE-HDL packaged netlist, KiCad conversion of Wiwynn_Tioga_Pass_MB.brd

J9T1  SCONN288_H44441003  SCONN  pkg PIP  page 78
  \12v\(1)  = P12V_NVDIMM_GHJ
  VSS(93)  = GND
  DQ(4)  = M_G_DQ<4>
  VSS(92)  = GND
  DQ(0)  = M_G_DQ<0>
  VSS(91)  = GND
  DQS9P  = M_G_DQS_DP<9>
  DQS9N  = M_G_DQS_DN<9>
  VSS(90)  = GND
  DQ(6)  = M_G_DQ<6>
  VSS(89)  = GND
  DQ(2)  = M_G_DQ<2>
  VSS(88)  = GND
  DQ(12)  = M_G_DQ<12>
  VSS(87)  = GND
  DQ(8)  = M_G_DQ<8>
  VSS(86)  = GND
  DQS10P  = M_G_DQS_DP<10>
  DQS10N  = M_G_DQS_DN<10>
  VSS(85)  = GND
  DQ(14)  = M_G_DQ<14>
  VSS(84)  = GND
  DQ(10)  = M_G_DQ<10>
  VSS(83)  = GND
  DQ(20)  = M_G_DQ<20>
  VSS(82)  = GND
  DQ(16)  = M_G_DQ<16>
  VSS(81)  = GND
  DQS11P  = M_G_DQS_DP<11>
  DQS11N  = M_G_DQS_DN<11>
  VSS(80)  = GND
  DQ(22)  = M_G_DQ<22>
  VSS(79)  = GND
  DQ(18)  = M_G_DQ<18>
  VSS(78)  = GND
  DQ(28)  = M_G_DQ<28>
  VSS(77)  = GND
  DQ(24)  = M_G_DQ<24>
  VSS(76)  = GND
  DQS12P  = M_G_DQS_DP<12>
  DQS12N  = M_G_DQS_DN<12>
  VSS(75)  = GND
  DQ(30)  = M_G_DQ<30>
  VSS(74)  = GND
  DQ(26)  = M_G_DQ<26>
  VSS(73)  = GND
  CB(4)  = M_G_ECC<4>
  VSS(72)  = GND
  CB(0)  = M_G_ECC<0>
  VSS(71)  = GND
  DQS17P  = M_G_DQS_DP<17>
  DQS17N  = M_G_DQS_DN<17>
  VSS(70)  = GND
  CB(6)  = M_G_ECC<6>
  VSS(69)  = GND
  CB(2)  = M_G_ECC<2>
  VSS(68)  = GND
  RESET_N  = M_GHJ_RST_N
  VDD(25)  = PVDDQ_GHJ
  CKE(0)  = M_G_CKE<2>
  VDD(24)  = PVDDQ_GHJ
  ACT_N  = M_G_ACT_N
  BG(0)  = M_G_BG<0>
  VDD(23)  = PVDDQ_GHJ
  A12  = M_G_MA<12>
  A9  = M_G_MA<9>
  VDD(22)  = PVDDQ_GHJ
  A8  = M_G_MA<8>
  A6  = M_G_MA<6>
  VDD(21)  = PVDDQ_GHJ
  A3  = M_G_MA<3>
  A1  = M_G_MA<1>
  VDD(20)  = PVDDQ_GHJ
  CK0P  = M_G_CLK_DP<2>
  CK0N  = M_G_CLK_DN<2>
  VDD(19)  = PVDDQ_GHJ
  VTT(1)  = PVTT_GHJ
  EVENT_N  = FM_DIMM_EVENT_COD_N
  A0  = M_G_MA<0>
  VDD(18)  = PVDDQ_GHJ
  BA(0)  = M_G_BA<0>
  A16_RAS_N  = M_G_MA<16>
  VDD(17)  = PVDDQ_GHJ
  S0_N  = M_G_CS_N<4>
  VDD(16)  = PVDDQ_GHJ
  A15_CAS_N  = M_G_MA<15>
  ODT(0)  = M_G_ODT<2>
  VDD(15)  = PVDDQ_GHJ
  S1_N  = M_G_CS_N<5>
  VDD(14)  = PVDDQ_GHJ
  ODT(1)  = M_G_ODT<3>
  VDD(13)  = PVDDQ_GHJ
  S2_N_C(0)  = M_G_CS_N<6>
  VSS(67)  = GND
  DQ(36)  = M_G_DQ<36>
  VSS(66)  = GND
  DQ(32)  = M_G_DQ<32>
  VSS(65)  = GND
  DQS13P  = M_G_DQS_DP<13>
  DQS13N  = M_G_DQS_DN<13>
  VSS(64)  = GND
  DQ(38)  = M_G_DQ<38>
  VSS(63)  = GND
  DQ(34)  = M_G_DQ<34>
  VSS(62)  = GND
  DQ(44)  = M_G_DQ<44>
  VSS(61)  = GND
  DQ(40)  = M_G_DQ<40>
  VSS(60)  = GND
  DQS14P  = M_G_DQS_DP<14>
  DQS14N  = M_G_DQS_DN<14>
  VSS(59)  = GND
  DQ(46)  = M_G_DQ<46>
  VSS(58)  = GND
  DQ(42)  = M_G_DQ<42>
  VSS(57)  = GND
  DQ(52)  = M_G_DQ<52>
  VSS(56)  = GND
  DQ(48)  = M_G_DQ<48>
  VSS(55)  = GND
  DQS15P  = M_G_DQS_DP<15>
  DQS15N  = M_G_DQS_DN<15>
  VSS(54)  = GND
  DQ(54)  = M_G_DQ<54>
  VSS(53)  = GND
  DQ(50)  = M_G_DQ<50>
  VSS(52)  = GND
  DQ(60)  = M_G_DQ<60>
  VSS(51)  = GND
  DQ(56)  = M_G_DQ<56>
  VSS(50)  = GND
  DQS16P  = M_G_DQS_DP<16>
  DQS16N  = M_G_DQS_DN<16>
  VSS(49)  = GND
  DQ(62)  = M_G_DQ<62>
  VSS(48)  = GND
  DQ(58)  = M_G_DQ<58>
  VSS(47)  = GND
  SA(0)  = PVPP_GHJ
  SA(1)  = GND
  SCL  = SMB_DDR_GHJ_VPP_SCL
  VPP(4)  = PVPP_GHJ
  VPP(3)  = PVPP_GHJ
  RFU(2)  = TP_CH_G_DIMM0_RFU_2
  \12v\(0)  = P12V_NVDIMM_GHJ
  VREFCA  = M_G_VREF
  VSS(46)  = GND
  DQ(5)  = M_G_DQ<5>
  VSS(45)  = GND
  DQ(1)  = M_G_DQ<1>
  VSS(44)  = GND
  DQS0N  = M_G_DQS_DN<0>
  DQS0P  = M_G_DQS_DP<0>
  VSS(43)  = GND
  DQ(7)  = M_G_DQ<7>
  VSS(42)  = GND
  DQ(3)  = M_G_DQ<3>
  VSS(41)  = GND
  DQ(13)  = M_G_DQ<13>
  VSS(40)  = GND
  DQ(9)  = M_G_DQ<9>
  VSS(39)  = GND
  DQS1N  = M_G_DQS_DN<1>
  DQS1P  = M_G_DQS_DP<1>
  VSS(38)  = GND
  DQ(15)  = M_G_DQ<15>
  VSS(37)  = GND
  DQ(11)  = M_G_DQ<11>
  VSS(36)  = GND
  DQ(21)  = M_G_DQ<21>
  VSS(35)  = GND
  DQ(17)  = M_G_DQ<17>
  VSS(34)  = GND
  DQS2N  = M_G_DQS_DN<2>
  DQS2P  = M_G_DQS_DP<2>
  VSS(33)  = GND
  DQ(23)  = M_G_DQ<23>
  VSS(32)  = GND
  DQ(19)  = M_G_DQ<19>
  VSS(31)  = GND
  DQ(29)  = M_G_DQ<29>
  VSS(30)  = GND
  DQ(25)  = M_G_DQ<25>
  VSS(29)  = GND
  DQS3N  = M_G_DQS_DN<3>
  DQS3P  = M_G_DQS_DP<3>
  VSS(28)  = GND
  DQ(31)  = M_G_DQ<31>
  VSS(27)  = GND
  DQ(27)  = M_G_DQ<27>
  VSS(26)  = GND
  CB(5)  = M_G_ECC<5>
  VSS(25)  = GND
  CB(1)  = M_G_ECC<1>
  VSS(24)  = GND
  DQS8N  = M_G_DQS_DN<8>
  DQS8P  = M_G_DQS_DP<8>
  VSS(23)  = GND
  CB(7)  = M_G_ECC<7>
  VSS(22)  = GND
  CB(3)  = M_G_ECC<3>
  VSS(21)  = GND
  CKE(1)  = M_G_CKE<3>
  VDD(12)  = PVDDQ_GHJ
  RFU(0)  = TP_CH_G_DIMM0_RFU_0
  VDD(11)  = PVDDQ_GHJ
  BG(1)  = M_G_BG<1>
  ALERT_N  = M_G_ALERT_N
  VDD(10)  = PVDDQ_GHJ
  A11  = M_G_MA<11>
  A7  = M_G_MA<7>
  VDD(9)  = PVDDQ_GHJ
  A5  = M_G_MA<5>
  A4  = M_G_MA<4>
  VDD(8)  = PVDDQ_GHJ
  A2  = M_G_MA<2>
  VDD(7)  = PVDDQ_GHJ
  CK1P  = M_G_CLK_DP<3>
  CK1N  = M_G_CLK_DN<3>
  VDD(6)  = PVDDQ_GHJ
  VTT(0)  = PVTT_GHJ
  PAR  = M_G_PAR
  VDD(5)  = PVDDQ_GHJ
  BA(1)  = M_G_BA<1>
  A10  = M_G_MA<10>
  VDD(4)  = PVDDQ_GHJ
  RFU(1)  = TP_CH_G_DIMM0_RFU_1
  A14_WE_N  = M_G_MA<14>
  VDD(3)  = PVDDQ_GHJ
  SAVE_N_NC  = FM_ADR_COMPLETE_GHJ_N
  VDD(2)  = PVDDQ_GHJ
  A13  = M_G_MA<13>
  VDD(1)  = PVDDQ_GHJ
  A17  = M_G_MA<17>
  C(2)  = M_G_C<2>
  VDD(0)  = PVDDQ_GHJ
  S3_N_C(1)  = M_G_CS_N<7>
  SA(2)  = GND
  VSS(20)  = GND
  DQ(37)  = M_G_DQ<37>
  VSS(19)  = GND
  DQ(33)  = M_G_DQ<33>
  VSS(18)  = GND
  DQS4N  = M_G_DQS_DN<4>
  DQS4P  = M_G_DQS_DP<4>
  VSS(17)  = GND
  DQ(39)  = M_G_DQ<39>
  VSS(16)  = GND
  DQ(35)  = M_G_DQ<35>
  VSS(15)  = GND
  DQ(45)  = M_G_DQ<45>
  VSS(14)  = GND
  DQ(41)  = M_G_DQ<41>
  VSS(13)  = GND
  DQS5N  = M_G_DQS_DN<5>
  DQS5P  = M_G_DQS_DP<5>
  VSS(12)  = GND
  DQ(47)  = M_G_DQ<47>
  VSS(11)  = GND
  DQ(43)  = M_G_DQ<43>
  VSS(10)  = GND
  DQ(53)  = M_G_DQ<53>
  VSS(9)  = GND
  DQ(49)  = M_G_DQ<49>
  VSS(8)  = GND
  DQS6N  = M_G_DQS_DN<6>
  DQS6P  = M_G_DQS_DP<6>
  VSS(7)  = GND
  DQ(55)  = M_G_DQ<55>
  VSS(6)  = GND
  DQ(51)  = M_G_DQ<51>
  VSS(5)  = GND
  DQ(61)  = M_G_DQ<61>
  VSS(4)  = GND
  DQ(57)  = M_G_DQ<57>
  VSS(3)  = GND
  DQS7N  = M_G_DQS_DN<7>
  DQS7P  = M_G_DQS_DP<7>
  VSS(2)  = GND
  DQ(63)  = M_G_DQ<63>
  VSS(1)  = GND
  DQ(59)  = M_G_DQ<59>
  VSS(0)  = GND
  VDDSPD  = PVPP_GHJ
  SDA  = SMB_DDR_GHJ_VPP_SDA
  VPP(1)  = PVPP_GHJ
  VPP(0)  = PVPP_GHJ
  VPP(2)  = PVPP_GHJ

(kicad_pcb
	(version 20260206)
	(generator "pcbnew")
	(generator_version "10.0")
	(general
		(thickness 1.6)
		(legacy_teardrops no)
	)
	(paper "A4")
	(title_block
		(title "Wiwynn_Tioga_Pass_MB.brd")
		(comment 1 "Tioga Pass / footprint 4084 of 4770 (J9T1), pads 1-50 of 291")
	)
	(layers
		(0 "F.Cu" signal "TOP")
		(4 "In1.Cu" signal "L2GND")
		(6 "In2.Cu" signal "L3")
		(8 "In3.Cu" signal "L4GND")
		(10 "In4.Cu" signal "L5")
		(12 "In5.Cu" signal "L6GND")
		(14 "In6.Cu" signal "L7VCC")
		(16 "In7.Cu" signal "L8VCC")
		(18 "In8.Cu" signal "L9GND")
		(20 "In9.Cu" signal "L10")
		(22 "In10.Cu" signal "L11GND")
		(24 "In11.Cu" signal "L12")
		(26 "In12.Cu" signal "L13GND")
		(2 "B.Cu" signal "BOTTOM")
		(9 "F.Adhes" user "F.Adhesive")
		(11 "B.Adhes" user "B.Adhesive")
		(13 "F.Paste" user "Package Geometry/Pastemask Top")
		(15 "B.Paste" user "Package Geometry/Pastemask Bottom")
		(5 "F.SilkS" user "Ref Des/Silkscreen Top")
		(7 "B.SilkS" user "Ref Des/Silkscreen Bottom")
		(1 "F.Mask" user "Board Geometry/Soldermask Top")
		(3 "B.Mask" user "Board Geometry/Soldermask Bottom")
		(17 "Dwgs.User" user "User.Drawings")
		(19 "Cmts.User" user "User.Comments")
		(21 "Eco1.User" user "User.Eco1")
		(23 "Eco2.User" user "User.Eco2")
		(25 "Edge.Cuts" user "Board Geometry/Outline")
		(27 "Margin" user)
		(31 "F.CrtYd" user "Package Geometry/Place Bound Top")
		(29 "B.CrtYd" user "Package Geometry/Place Bound Bottom")
		(35 "F.Fab" user "Ref Des/Assembly Top")
		(33 "B.Fab" user "Ref Des/Assembly Bottom")
	)
	(footprint ""
		(layer "B.Cu")
		(at 29.699458 -24.824182 90)
		(property "Reference" "J9T1"
			(at 2.200148 39.261542 0)
			(unlocked yes)
			(layer "B.SilkS")
			(effects
				(font
					(size 0.7874 0.5842)
					(thickness 0.1524)
				)
				(justify left mirror)
			)
		)
		(property "Value" ""
			(at 0 0 90)
			(layer "B.Fab")
			(effects
				(font
					(size 1.27 1.27)
				)
				(justify mirror)
			)
		)
		(duplicate_pad_numbers_are_jumpers no)
		(pad "" thru_hole circle
			(at -2.29997 -5.649976 270)
			(size 2.8194 2.8194)
			(drill 2.4384)
			(layers "*.Cu" "*.Mask")
			(remove_unused_layers no)
			(clearance 0.127)
			(thermal_gap 0.127)
		)
		(pad "" thru_hole oval
			(at -2.29997 68.90004 270)
			(size 2.8194 1.5748)
			(drill oval 2.4384 1.1938)
			(layers "*.Cu" "*.Mask")
			(remove_unused_layers no)
			(clearance 0.127)
			(thermal_gap 0.127)
		)
		(pad "" thru_hole circle
			(at -2.29997 132.299964 270)
			(size 2.8194 2.8194)
			(drill 2.4384)
			(layers "*.Cu" "*.Mask")
			(remove_unused_layers no)
			(clearance 0.127)
			(thermal_gap 0.127)
		)
		(pad "1" smd rect
			(at 0 0 270)
			(size 1.8034 0.508)
			(layers "B.Cu" "B.Mask" "B.Paste")
			(net "P12V_NVDIMM_GHJ")
		)
		(pad "2" smd rect
			(at 0 0.849884 270)
			(size 1.8034 0.508)
			(layers "B.Cu" "B.Mask" "B.Paste")
			(net "GND")
		)
		(pad "3" smd rect
			(at 0 1.700022 270)
			(size 1.8034 0.508)
			(layers "B.Cu" "B.Mask" "B.Paste")
			(net "M_G_DQ<4>")
		)
		(pad "4" smd rect
			(at 0 2.549906 270)
			(size 1.8034 0.508)
			(layers "B.Cu" "B.Mask" "B.Paste")
			(net "GND")
		)
		(pad "5" smd rect
			(at 0 3.400044 270)
			(size 1.8034 0.508)
			(layers "B.Cu" "B.Mask" "B.Paste")
			(net "M_G_DQ<0>")
		)
		(pad "6" smd rect
			(at 0 4.249928 270)
			(size 1.8034 0.508)
			(layers "B.Cu" "B.Mask" "B.Paste")
			(net "GND")
		)
		(pad "7" smd rect
			(at 0 5.100066 270)
			(size 1.8034 0.508)
			(layers "B.Cu" "B.Mask" "B.Paste")
			(net "M_G_DQS_DP<9>")
		)
		(pad "8" smd rect
			(at 0 5.94995 270)
			(size 1.8034 0.508)
			(layers "B.Cu" "B.Mask" "B.Paste")
			(net "M_G_DQS_DN<9>")
		)
		(pad "9" smd rect
			(at 0 6.800088 270)
			(size 1.8034 0.508)
			(layers "B.Cu" "B.Mask" "B.Paste")
			(net "GND")
		)
		(pad "10" smd rect
			(at 0 7.649972 270)
			(size 1.8034 0.508)
			(layers "B.Cu" "B.Mask" "B.Paste")
			(net "M_G_DQ<6>")
		)
		(pad "11" smd rect
			(at 0 8.50011 270)
			(size 1.8034 0.508)
			(layers "B.Cu" "B.Mask" "B.Paste")
			(net "GND")
		)
		(pad "12" smd rect
			(at 0 9.349994 270)
			(size 1.8034 0.508)
			(layers "B.Cu" "B.Mask" "B.Paste")
			(net "M_G_DQ<2>")
		)
		(pad "13" smd rect
			(at 0 10.199878 270)
			(size 1.8034 0.508)
			(layers "B.Cu" "B.Mask" "B.Paste")
			(net "GND")
		)
		(pad "14" smd rect
			(at 0 11.050016 270)
			(size 1.8034 0.508)
			(layers "B.Cu" "B.Mask" "B.Paste")
			(net "M_G_DQ<12>")
		)
		(pad "15" smd rect
			(at 0 11.8999 270)
			(size 1.8034 0.508)
			(layers "B.Cu" "B.Mask" "B.Paste")
			(net "GND")
		)
		(pad "16" smd rect
			(at 0 12.750038 270)
			(size 1.8034 0.508)
			(layers "B.Cu" "B.Mask" "B.Paste")
			(net "M_G_DQ<8>")
		)
		(pad "17" smd rect
			(at 0 13.599922 270)
			(size 1.8034 0.508)
			(layers "B.Cu" "B.Mask" "B.Paste")
			(net "GND")
		)
		(pad "18" smd rect
			(at 0 14.45006 270)
			(size 1.8034 0.508)
			(layers "B.Cu" "B.Mask" "B.Paste")
			(net "M_G_DQS_DP<10>")
		)
		(pad "19" smd rect
			(at 0 15.299944 270)
			(size 1.8034 0.508)
			(layers "B.Cu" "B.Mask" "B.Paste")
			(net "M_G_DQS_DN<10>")
		)
		(pad "20" smd rect
			(at 0 16.150082 270)
			(size 1.8034 0.508)
			(layers "B.Cu" "B.Mask" "B.Paste")
			(net "GND")
		)
		(pad "21" smd rect
			(at 0 16.999966 270)
			(size 1.8034 0.508)
			(layers "B.Cu" "B.Mask" "B.Paste")
			(net "M_G_DQ<14>")
		)
		(pad "22" smd rect
			(at 0 17.850104 270)
			(size 1.8034 0.508)
			(layers "B.Cu" "B.Mask" "B.Paste")
			(net "GND")
		)
		(pad "23" smd rect
			(at 0 18.699988 270)
			(size 1.8034 0.508)
			(layers "B.Cu" "B.Mask" "B.Paste")
			(net "M_G_DQ<10>")
		)
		(pad "24" smd rect
			(at 0 19.550126 270)
			(size 1.8034 0.508)
			(layers "B.Cu" "B.Mask" "B.Paste")
			(net "GND")
		)
		(pad "25" smd rect
			(at 0 20.40001 270)
			(size 1.8034 0.508)
			(layers "B.Cu" "B.Mask" "B.Paste")
			(net "M_G_DQ<20>")
		)
		(pad "26" smd rect
			(at 0 21.249894 270)
			(size 1.8034 0.508)
			(layers "B.Cu" "B.Mask" "B.Paste")
			(net "GND")
		)
		(pad "27" smd rect
			(at 0 22.100032 270)
			(size 1.8034 0.508)
			(layers "B.Cu" "B.Mask" "B.Paste")
			(net "M_G_DQ<16>")
		)
		(pad "28" smd rect
			(at 0 22.949916 270)
			(size 1.8034 0.508)
			(layers "B.Cu" "B.Mask" "B.Paste")
			(net "GND")
		)
		(pad "29" smd rect
			(at 0 23.800054 270)
			(size 1.8034 0.508)
			(layers "B.Cu" "B.Mask" "B.Paste")
			(net "M_G_DQS_DP<11>")
		)
		(pad "30" smd rect
			(at 0 24.649938 270)
			(size 1.8034 0.508)
			(layers "B.Cu" "B.Mask" "B.Paste")
			(net "M_G_DQS_DN<11>")
		)
		(pad "31" smd rect
			(at 0 25.500076 270)
			(size 1.8034 0.508)
			(layers "B.Cu" "B.Mask" "B.Paste")
			(net "GND")
		)
		(pad "32" smd rect
			(at 0 26.34996 270)
			(size 1.8034 0.508)
			(layers "B.Cu" "B.Mask" "B.Paste")
			(net "M_G_DQ<22>")
		)
		(pad "33" smd rect
			(at 0 27.200098 270)
			(size 1.8034 0.508)
			(layers "B.Cu" "B.Mask" "B.Paste")
			(net "GND")
		)
		(pad "34" smd rect
			(at 0 28.049982 270)
			(size 1.8034 0.508)
			(layers "B.Cu" "B.Mask" "B.Paste")
			(net "M_G_DQ<18>")
		)
		(pad "35" smd rect
			(at 0 28.90012 270)
			(size 1.8034 0.508)
			(layers "B.Cu" "B.Mask" "B.Paste")
			(net "GND")
		)
		(pad "36" smd rect
			(at 0 29.750004 270)
			(size 1.8034 0.508)
			(layers "B.Cu" "B.Mask" "B.Paste")
			(net "M_G_DQ<28>")
		)
		(pad "37" smd rect
			(at 0 30.599888 270)
			(size 1.8034 0.508)
			(layers "B.Cu" "B.Mask" "B.Paste")
			(net "GND")
		)
		(pad "38" smd rect
			(at 0 31.450026 270)
			(size 1.8034 0.508)
			(layers "B.Cu" "B.Mask" "B.Paste")
			(net "M_G_DQ<24>")
		)
		(pad "39" smd rect
			(at 0 32.29991 270)
			(size 1.8034 0.508)
			(layers "B.Cu" "B.Mask" "B.Paste")
			(net "GND")
		)
		(pad "40" smd rect
			(at 0 33.150048 270)
			(size 1.8034 0.508)
			(layers "B.Cu" "B.Mask" "B.Paste")
			(net "M_G_DQS_DP<12>")
		)
		(pad "41" smd rect
			(at 0 33.999932 270)
			(size 1.8034 0.508)
			(layers "B.Cu" "B.Mask" "B.Paste")
			(net "M_G_DQS_DN<12>")
		)
		(pad "42" smd rect
			(at 0 34.85007 270)
			(size 1.8034 0.508)
			(layers "B.Cu" "B.Mask" "B.Paste")
			(net "GND")
		)
		(pad "43" smd rect
			(at 0 35.699954 270)
			(size 1.8034 0.508)
			(layers "B.Cu" "B.Mask" "B.Paste")
			(net "M_G_DQ<30>")
		)
		(pad "44" smd rect
			(at 0 36.550092 270)
			(size 1.8034 0.508)
			(layers "B.Cu" "B.Mask" "B.Paste")
			(net "GND")
		)
		(pad "45" smd rect
			(at 0 37.399976 270)
			(size 1.8034 0.508)
			(layers "B.Cu" "B.Mask" "B.Paste")
			(net "M_G_DQ<26>")
		)
		(pad "46" smd rect
			(at 0 38.250114 270)
			(size 1.8034 0.508)
			(layers "B.Cu" "B.Mask" "B.Paste")
			(net "GND")
		)
		(pad "47" smd rect
			(at 0 39.099998 270)
			(size 1.8034 0.508)
			(layers "B.Cu" "B.Mask" "B.Paste")
			(net "M_G_ECC<4>")
		)
	)
)
